(kicad_pcb
	(version 20260206)
	(generator "pcbnew")
	(generator_version "10.0")
	(general
		(thickness 1.6)
		(legacy_teardrops no)
	)
	(paper "A4")
	(title_block
		(title "Wiwynn_Tioga_Pass_MB.brd")
		(comment 1 "Tioga Pass / footprint 1728 of 4770 (EU7B1), pads 1-43 of 43")
	)
	(layers
		(0 "F.Cu" signal "TOP")
		(4 "In1.Cu" signal "L2GND")
		(6 "In2.Cu" signal "L3")
		(8 "In3.Cu" signal "L4GND")
		(10 "In4.Cu" signal "L5")
		(12 "In5.Cu" signal "L6GND")
		(14 "In6.Cu" signal "L7VCC")
		(16 "In7.Cu" signal "L8VCC")
		(18 "In8.Cu" signal "L9GND")
		(20 "In9.Cu" signal "L10")
		(22 "In10.Cu" signal "L11GND")
		(24 "In11.Cu" signal "L12")
		(26 "In12.Cu" signal "L13GND")
		(2 "B.Cu" signal "BOTTOM")
		(9 "F.Adhes" user "F.Adhesive")
		(11 "B.Adhes" user "B.Adhesive")
		(13 "F.Paste" user "Package Geometry/Pastemask Top")
		(15 "B.Paste" user "Package Geometry/Pastemask Bottom")
		(5 "F.SilkS" user "Ref Des/Silkscreen Top")
		(7 "B.SilkS" user "Ref Des/Silkscreen Bottom")
		(1 "F.Mask" user "Board Geometry/Soldermask Top")
		(3 "B.Mask" user "Board Geometry/Soldermask Bottom")
		(17 "Dwgs.User" user "User.Drawings")
		(19 "Cmts.User" user "User.Comments")
		(21 "Eco1.User" user "User.Eco1")
		(23 "Eco2.User" user "User.Eco2")
		(25 "Edge.Cuts" user "Board Geometry/Outline")
		(27 "Margin" user)
		(31 "F.CrtYd" user "Package Geometry/Place Bound Top")
		(29 "B.CrtYd" user "Package Geometry/Place Bound Bottom")
		(35 "F.Fab" user "Ref Des/Assembly Top")
		(33 "B.Fab" user "Ref Des/Assembly Bottom")
	)
	(footprint ""
		(layer "F.Cu")
		(at 344.043 -132.8547 90)
		(property "Reference" "EU7B1"
			(at 5.29463 -1.27 0)
			(unlocked yes)
			(layer "F.SilkS")
			(effects
				(font
					(size 0.7874 0.5842)
					(thickness 0.1524)
				)
				(justify left)
			)
		)
		(property "Value" ""
			(at 0 0 90)
			(layer "F.Fab")
			(effects
				(font
					(size 1.27 1.27)
				)
			)
		)
		(duplicate_pad_numbers_are_jumpers no)
		(pad "1" smd custom
			(at -2.8321 -2.249932 90)
			(size 0.06985 0.06985)
			(layers "F.Cu" "F.Mask" "F.Paste")
			(net "VR_PVPP_DEF_SS")
			(options
				(clearance outline)
				(anchor circle)
			)
			(primitives
				(gr_poly
					(pts
						(arc
							(start 0.2413 -0.1397)
							(mid 0.381 0)
							(end 0.2413 0.1397)
						)
						(xy -0.381 0.1397) (xy -0.381 -0.1397)
					)
					(width 0)
					(fill yes)
				)
			)
		)
		(pad "2" smd custom
			(at -2.8321 -1.75006 90)
			(size 0.06985 0.06985)
			(layers "F.Cu" "F.Mask" "F.Paste")
			(net "VR_FB_PVPP_DEF")
			(options
				(clearance outline)
				(anchor circle)
			)
			(primitives
				(gr_poly
					(pts
						(arc
							(start 0.2413 -0.1397)
							(mid 0.381 0)
							(end 0.2413 0.1397)
						)
						(xy -0.381 0.1397) (xy -0.381 -0.1397)
					)
					(width 0)
					(fill yes)
				)
			)
		)
		(pad "3" smd custom
			(at -2.8321 -1.249934 90)
			(size 0.06985 0.06985)
			(layers "F.Cu" "F.Mask" "F.Paste")
			(net "VR_COMP_PVPP_DEF_3")
			(options
				(clearance outline)
				(anchor circle)
			)
			(primitives
				(gr_poly
					(pts
						(arc
							(start 0.2413 -0.1397)
							(mid 0.381 0)
							(end 0.2413 0.1397)
						)
						(xy -0.381 0.1397) (xy -0.381 -0.1397)
					)
					(width 0)
					(fill yes)
				)
			)
		)
		(pad "4" smd custom
			(at -2.8321 -0.750062 90)
			(size 0.06985 0.06985)
			(layers "F.Cu" "F.Mask" "F.Paste")
			(net "VR_PVPP_DEF_ISET")
			(options
				(clearance outline)
				(anchor circle)
			)
			(primitives
				(gr_poly
					(pts
						(arc
							(start 0.2413 -0.1397)
							(mid 0.381 0)
							(end 0.2413 0.1397)
						)
						(xy -0.381 0.1397) (xy -0.381 -0.1397)
					)
					(width 0)
					(fill yes)
				)
			)
		)
		(pad "5" smd custom
			(at -2.8321 -0.249936 90)
			(size 0.06985 0.06985)
			(layers "F.Cu" "F.Mask" "F.Paste")
			(net "AGND_PVPP_DEF")
			(options
				(clearance outline)
				(anchor circle)
			)
			(primitives
				(gr_poly
					(pts
						(arc
							(start 0.2413 -0.1397)
							(mid 0.381 0)
							(end 0.2413 0.1397)
						)
						(xy -0.381 0.1397) (xy -0.381 -0.1397)
					)
					(width 0)
					(fill yes)
				)
			)
		)
		(pad "6" smd custom
			(at -2.8321 0.249936 90)
			(size 0.06985 0.06985)
			(layers "F.Cu" "F.Mask" "F.Paste")
			(net "AGND_PVPP_DEF")
			(options
				(clearance outline)
				(anchor circle)
			)
			(primitives
				(gr_poly
					(pts
						(arc
							(start 0.2413 -0.1397)
							(mid 0.381 0)
							(end 0.2413 0.1397)
						)
						(xy -0.381 0.1397) (xy -0.381 -0.1397)
					)
					(width 0)
					(fill yes)
				)
			)
		)
		(pad "7" smd custom
			(at -2.8321 0.750062 90)
			(size 0.06985 0.06985)
			(layers "F.Cu" "F.Mask" "F.Paste")
			(net "PWRGD_PVPP_DEF_R")
			(options
				(clearance outline)
				(anchor circle)
			)
			(primitives
				(gr_poly
					(pts
						(arc
							(start 0.2413 -0.1397)
							(mid 0.381 0)
							(end 0.2413 0.1397)
						)
						(xy -0.381 0.1397) (xy -0.381 -0.1397)
					)
					(width 0)
					(fill yes)
				)
			)
		)
		(pad "8" smd custom
			(at -2.8321 1.249934 90)
			(size 0.06985 0.06985)
			(layers "F.Cu" "F.Mask" "F.Paste")
			(net "VR_FET_SW_P12V_STBY_PVPP_DEF")
			(options
				(clearance outline)
				(anchor circle)
			)
			(primitives
				(gr_poly
					(pts
						(arc
							(start 0.2413 -0.1397)
							(mid 0.381 0)
							(end 0.2413 0.1397)
						)
						(xy -0.381 0.1397) (xy -0.381 -0.1397)
					)
					(width 0)
					(fill yes)
				)
			)
		)
		(pad "9" smd custom
			(at -2.8321 1.75006 90)
			(size 0.06985 0.06985)
			(layers "F.Cu" "F.Mask" "F.Paste")
			(net "VR_FET_SW_P12V_STBY_PVPP_DEF")
			(options
				(clearance outline)
				(anchor circle)
			)
			(primitives
				(gr_poly
					(pts
						(arc
							(start 0.2413 -0.1397)
							(mid 0.381 0)
							(end 0.2413 0.1397)
						)
						(xy -0.381 0.1397) (xy -0.381 -0.1397)
					)
					(width 0)
					(fill yes)
				)
			)
		)
		(pad "10" smd custom
			(at -2.8321 2.249932 90)
			(size 0.06985 0.06985)
			(layers "F.Cu" "F.Mask" "F.Paste")
			(net "VR_FET_SW_P12V_STBY_PVPP_DEF")
			(options
				(clearance outline)
				(anchor circle)
			)
			(primitives
				(gr_poly
					(pts
						(arc
							(start 0.2413 -0.1397)
							(mid 0.381 0)
							(end 0.2413 0.1397)
						)
						(xy -0.381 0.1397) (xy -0.381 -0.1397)
					)
					(width 0)
					(fill yes)
				)
			)
		)
		(pad "11" smd custom
			(at -2.249932 2.8321 90)
			(size 0.06985 0.06985)
			(layers "F.Cu" "F.Mask" "F.Paste")
			(net "VR_FET_SW_P12V_STBY_PVPP_DEF")
			(options
				(clearance outline)
				(anchor circle)
			)
			(primitives
				(gr_poly
					(pts
						(arc
							(start -0.1397 -0.2413)
							(mid 0 -0.381)
							(end 0.1397 -0.2413)
						)
						(xy 0.1397 0.381) (xy -0.1397 0.381)
					)
					(width 0)
					(fill yes)
				)
			)
		)
		(pad "12" smd custom
			(at -1.75006 2.8321 90)
			(size 0.06985 0.06985)
			(layers "F.Cu" "F.Mask" "F.Paste")
			(net "VR_FET_SW_P12V_STBY_PVPP_DEF")
			(options
				(clearance outline)
				(anchor circle)
			)
			(primitives
				(gr_poly
					(pts
						(arc
							(start -0.1397 -0.2413)
							(mid 0 -0.381)
							(end 0.1397 -0.2413)
						)
						(xy 0.1397 0.381) (xy -0.1397 0.381)
					)
					(width 0)
					(fill yes)
				)
			)
		)
		(pad "13" smd custom
			(at -1.249934 2.8321 90)
			(size 0.06985 0.06985)
			(layers "F.Cu" "F.Mask" "F.Paste")
			(net "VR_FET_SW_P12V_STBY_PVPP_DEF")
			(options
				(clearance outline)
				(anchor circle)
			)
			(primitives
				(gr_poly
					(pts
						(arc
							(start -0.1397 -0.2413)
							(mid 0 -0.381)
							(end 0.1397 -0.2413)
						)
						(xy 0.1397 0.381) (xy -0.1397 0.381)
					)
					(width 0)
					(fill yes)
				)
			)
		)
		(pad "14" smd custom
			(at -0.750062 2.8321 90)
			(size 0.06985 0.06985)
			(layers "F.Cu" "F.Mask" "F.Paste")
			(net "VR_FET_SW_P12V_STBY_PVPP_DEF")
			(options
				(clearance outline)
				(anchor circle)
			)
			(primitives
				(gr_poly
					(pts
						(arc
							(start -0.1397 -0.2413)
							(mid 0 -0.381)
							(end 0.1397 -0.2413)
						)
						(xy 0.1397 0.381) (xy -0.1397 0.381)
					)
					(width 0)
					(fill yes)
				)
			)
		)
		(pad "15" smd custom
			(at -0.249936 2.8321 90)
			(size 0.06985 0.06985)
			(layers "F.Cu" "F.Mask" "F.Paste")
			(net "VR_PVPP_DEF_PHASE")
			(options
				(clearance outline)
				(anchor circle)
			)
			(primitives
				(gr_poly
					(pts
						(arc
							(start -0.1397 -0.2413)
							(mid 0 -0.381)
							(end 0.1397 -0.2413)
						)
						(xy 0.1397 0.381) (xy -0.1397 0.381)
					)
					(width 0)
					(fill yes)
				)
			)
		)
		(pad "16" smd custom
			(at 0.249936 2.8321 90)
			(size 0.06985 0.06985)
			(layers "F.Cu" "F.Mask" "F.Paste")
			(net "GND")
			(options
				(clearance outline)
				(anchor circle)
			)
			(primitives
				(gr_poly
					(pts
						(arc
							(start -0.1397 -0.2413)
							(mid 0 -0.381)
							(end 0.1397 -0.2413)
						)
						(xy 0.1397 0.381) (xy -0.1397 0.381)
					)
					(width 0)
					(fill yes)
				)
			)
		)
		(pad "17" smd custom
			(at 0.750062 2.8321 90)
			(size 0.06985 0.06985)
			(layers "F.Cu" "F.Mask" "F.Paste")
			(net "GND")
			(options
				(clearance outline)
				(anchor circle)
			)
			(primitives
				(gr_poly
					(pts
						(arc
							(start -0.1397 -0.2413)
							(mid 0 -0.381)
							(end 0.1397 -0.2413)
						)
						(xy 0.1397 0.381) (xy -0.1397 0.381)
					)
					(width 0)
					(fill yes)
				)
			)
		)
		(pad "18" smd custom
			(at 1.249934 2.8321 90)
			(size 0.06985 0.06985)
			(layers "F.Cu" "F.Mask" "F.Paste")
			(net "GND")
			(options
				(clearance outline)
				(anchor circle)
			)
			(primitives
				(gr_poly
					(pts
						(arc
							(start -0.1397 -0.2413)
							(mid 0 -0.381)
							(end 0.1397 -0.2413)
						)
						(xy 0.1397 0.381) (xy -0.1397 0.381)
					)
					(width 0)
					(fill yes)
				)
			)
		)
		(pad "19" smd custom
			(at 1.75006 2.8321 90)
			(size 0.06985 0.06985)
			(layers "F.Cu" "F.Mask" "F.Paste")
			(net "GND")
			(options
				(clearance outline)
				(anchor circle)
			)
			(primitives
				(gr_poly
					(pts
						(arc
							(start -0.1397 -0.2413)
							(mid 0 -0.381)
							(end 0.1397 -0.2413)
						)
						(xy 0.1397 0.381) (xy -0.1397 0.381)
					)
					(width 0)
					(fill yes)
				)
			)
		)
		(pad "20" smd custom
			(at 2.249932 2.8321 90)
			(size 0.06985 0.06985)
			(layers "F.Cu" "F.Mask" "F.Paste")
			(net "GND")
			(options
				(clearance outline)
				(anchor circle)
			)
			(primitives
				(gr_poly
					(pts
						(arc
							(start -0.1397 -0.2413)
							(mid 0 -0.381)
							(end 0.1397 -0.2413)
						)
						(xy 0.1397 0.381) (xy -0.1397 0.381)
					)
					(width 0)
					(fill yes)
				)
			)
		)
		(pad "21" smd custom
			(at 2.8321 2.249932 90)
			(size 0.06985 0.06985)
			(layers "F.Cu" "F.Mask" "F.Paste")
			(net "GND")
			(options
				(clearance outline)
				(anchor circle)
			)
			(primitives
				(gr_poly
					(pts
						(arc
							(start -0.2413 0.1397)
							(mid -0.381 0)
							(end -0.2413 -0.1397)
						)
						(xy 0.381 -0.1397) (xy 0.381 0.1397)
					)
					(width 0)
					(fill yes)
				)
			)
		)
		(pad "22" smd custom
			(at 2.8321 1.75006 90)
			(size 0.06985 0.06985)
			(layers "F.Cu" "F.Mask" "F.Paste")
			(net "GND")
			(options
				(clearance outline)
				(anchor circle)
			)
			(primitives
				(gr_poly
					(pts
						(arc
							(start -0.2413 0.1397)
							(mid -0.381 0)
							(end -0.2413 -0.1397)
						)
						(xy 0.381 -0.1397) (xy 0.381 0.1397)
					)
					(width 0)
					(fill yes)
				)
			)
		)
		(pad "23" smd custom
			(at 2.8321 1.249934 90)
			(size 0.06985 0.06985)
			(layers "F.Cu" "F.Mask" "F.Paste")
			(net "GND")
			(options
				(clearance outline)
				(anchor circle)
			)
			(primitives
				(gr_poly
					(pts
						(arc
							(start -0.2413 0.1397)
							(mid -0.381 0)
							(end -0.2413 -0.1397)
						)
						(xy 0.381 -0.1397) (xy 0.381 0.1397)
					)
					(width 0)
					(fill yes)
				)
			)
		)
		(pad "24" smd custom
			(at 2.8321 0.750062 90)
			(size 0.06985 0.06985)
			(layers "F.Cu" "F.Mask" "F.Paste")
			(net "GND")
			(options
				(clearance outline)
				(anchor circle)
			)
			(primitives
				(gr_poly
					(pts
						(arc
							(start -0.2413 0.1397)
							(mid -0.381 0)
							(end -0.2413 -0.1397)
						)
						(xy 0.381 -0.1397) (xy 0.381 0.1397)
					)
					(width 0)
					(fill yes)
				)
			)
		)
		(pad "25" smd custom
			(at 2.8321 0.249936 90)
			(size 0.06985 0.06985)
			(layers "F.Cu" "F.Mask" "F.Paste")
			(net "GND")
			(options
				(clearance outline)
				(anchor circle)
			)
			(primitives
				(gr_poly
					(pts
						(arc
							(start -0.2413 0.1397)
							(mid -0.381 0)
							(end -0.2413 -0.1397)
						)
						(xy 0.381 -0.1397) (xy 0.381 0.1397)
					)
					(width 0)
					(fill yes)
				)
			)
		)
		(pad "26" smd custom
			(at 2.8321 -0.249936 90)
			(size 0.06985 0.06985)
			(layers "F.Cu" "F.Mask" "F.Paste")
			(net "GND")
			(options
				(clearance outline)
				(anchor circle)
			)
			(primitives
				(gr_poly
					(pts
						(arc
							(start -0.2413 0.1397)
							(mid -0.381 0)
							(end -0.2413 -0.1397)
						)
						(xy 0.381 -0.1397) (xy 0.381 0.1397)
					)
					(width 0)
					(fill yes)
				)
			)
		)
		(pad "27" smd custom
			(at 2.8321 -0.750062 90)
			(size 0.06985 0.06985)
			(layers "F.Cu" "F.Mask" "F.Paste")
			(net "GND")
			(options
				(clearance outline)
				(anchor circle)
			)
			(primitives
				(gr_poly
					(pts
						(arc
							(start -0.2413 0.1397)
							(mid -0.381 0)
							(end -0.2413 -0.1397)
						)
						(xy 0.381 -0.1397) (xy 0.381 0.1397)
					)
					(width 0)
					(fill yes)
				)
			)
		)
		(pad "28" smd custom
			(at 2.8321 -1.249934 90)
			(size 0.06985 0.06985)
			(layers "F.Cu" "F.Mask" "F.Paste")
			(net "GND")
			(options
				(clearance outline)
				(anchor circle)
			)
			(primitives
				(gr_poly
					(pts
						(arc
							(start -0.2413 0.1397)
							(mid -0.381 0)
							(end -0.2413 -0.1397)
						)
						(xy 0.381 -0.1397) (xy 0.381 0.1397)
					)
					(width 0)
					(fill yes)
				)
			)
		)
		(pad "29" smd custom
			(at 2.8321 -1.75006 90)
			(size 0.06985 0.06985)
			(layers "F.Cu" "F.Mask" "F.Paste")
			(net "VR_PVPP_DEF_PHASE")
			(options
				(clearance outline)
				(anchor circle)
			)
			(primitives
				(gr_poly
					(pts
						(arc
							(start -0.2413 0.1397)
							(mid -0.381 0)
							(end -0.2413 -0.1397)
						)
						(xy 0.381 -0.1397) (xy 0.381 0.1397)
					)
					(width 0)
					(fill yes)
				)
			)
		)
		(pad "30" smd custom
			(at 2.8321 -2.249932 90)
			(size 0.06985 0.06985)
			(layers "F.Cu" "F.Mask" "F.Paste")
			(net "VR_PVPP_DEF_PHASE")
			(options
				(clearance outline)
				(anchor circle)
			)
			(primitives
				(gr_poly
					(pts
						(arc
							(start -0.2413 0.1397)
							(mid -0.381 0)
							(end -0.2413 -0.1397)
						)
						(xy 0.381 -0.1397) (xy 0.381 0.1397)
					)
					(width 0)
					(fill yes)
				)
			)
		)
		(pad "31" smd custom
			(at 2.249932 -2.8321 90)
			(size 0.06985 0.06985)
			(layers "F.Cu" "F.Mask" "F.Paste")
			(net "VR_PVPP_DEF_PHASE")
			(options
				(clearance outline)
				(anchor circle)
			)
			(primitives
				(gr_poly
					(pts
						(arc
							(start 0.1397 0.2413)
							(mid 0 0.381)
							(end -0.1397 0.2413)
						)
						(xy -0.1397 -0.381) (xy 0.1397 -0.381)
					)
					(width 0)
					(fill yes)
				)
			)
		)
		(pad "32" smd custom
			(at 1.75006 -2.8321 90)
			(size 0.06985 0.06985)
			(layers "F.Cu" "F.Mask" "F.Paste")
			(net "VR_PVPP_DEF_PHASE")
			(options
				(clearance outline)
				(anchor circle)
			)
			(primitives
				(gr_poly
					(pts
						(arc
							(start 0.1397 0.2413)
							(mid 0 0.381)
							(end -0.1397 0.2413)
						)
						(xy -0.1397 -0.381) (xy 0.1397 -0.381)
					)
					(width 0)
					(fill yes)
				)
			)
		)
		(pad "33" smd custom
			(at 1.249934 -2.8321 90)
			(size 0.06985 0.06985)
			(layers "F.Cu" "F.Mask" "F.Paste")
			(net "VR_PVPP_DEF_PHASE")
			(options
				(clearance outline)
				(anchor circle)
			)
			(primitives
				(gr_poly
					(pts
						(arc
							(start 0.1397 0.2413)
							(mid 0 0.381)
							(end -0.1397 0.2413)
						)
						(xy -0.1397 -0.381) (xy 0.1397 -0.381)
					)
					(width 0)
					(fill yes)
				)
			)
		)
		(pad "34" smd custom
			(at 0.750062 -2.8321 90)
			(size 0.06985 0.06985)
			(layers "F.Cu" "F.Mask" "F.Paste")
			(net "VR_PVPP_DEF_PHASE")
			(options
				(clearance outline)
				(anchor circle)
			)
			(primitives
				(gr_poly
					(pts
						(arc
							(start 0.1397 0.2413)
							(mid 0 0.381)
							(end -0.1397 0.2413)
						)
						(xy -0.1397 -0.381) (xy 0.1397 -0.381)
					)
					(width 0)
					(fill yes)
				)
			)
		)
		(pad "35" smd custom
			(at 0.249936 -2.8321 90)
			(size 0.06985 0.06985)
			(layers "F.Cu" "F.Mask" "F.Paste")
			(net "VR_PVPP_DEF_PHASE")
			(options
				(clearance outline)
				(anchor circle)
			)
			(primitives
				(gr_poly
					(pts
						(arc
							(start 0.1397 0.2413)
							(mid 0 0.381)
							(end -0.1397 0.2413)
						)
						(xy -0.1397 -0.381) (xy 0.1397 -0.381)
					)
					(width 0)
					(fill yes)
				)
			)
		)
		(pad "36" smd custom
			(at -0.249936 -2.8321 90)
			(size 0.06985 0.06985)
			(layers "F.Cu" "F.Mask" "F.Paste")
			(net "VR_PVPP_DEF_BOOT")
			(options
				(clearance outline)
				(anchor circle)
			)
			(primitives
				(gr_poly
					(pts
						(arc
							(start 0.1397 0.2413)
							(mid 0 0.381)
							(end -0.1397 0.2413)
						)
						(xy -0.1397 -0.381) (xy 0.1397 -0.381)
					)
					(width 0)
					(fill yes)
				)
			)
		)
		(pad "37" smd custom
			(at -0.750062 -2.8321 90)
			(size 0.06985 0.06985)
			(layers "F.Cu" "F.Mask" "F.Paste")
			(net "GND")
			(options
				(clearance outline)
				(anchor circle)
			)
			(primitives
				(gr_poly
					(pts
						(arc
							(start 0.1397 0.2413)
							(mid 0 0.381)
							(end -0.1397 0.2413)
						)
						(xy -0.1397 -0.381) (xy 0.1397 -0.381)
					)
					(width 0)
					(fill yes)
				)
			)
		)
		(pad "38" smd custom
			(at -1.249934 -2.8321 90)
			(size 0.06985 0.06985)
			(layers "F.Cu" "F.Mask" "F.Paste")
			(net "VR_VB_PVPP_DEF")
			(options
				(clearance outline)
				(anchor circle)
			)
			(primitives
				(gr_poly
					(pts
						(arc
							(start 0.1397 0.2413)
							(mid 0 0.381)
							(end -0.1397 0.2413)
						)
						(xy -0.1397 -0.381) (xy 0.1397 -0.381)
					)
					(width 0)
					(fill yes)
				)
			)
		)
		(pad "39" smd custom
			(at -1.75006 -2.8321 90)
			(size 0.06985 0.06985)
			(layers "F.Cu" "F.Mask" "F.Paste")
			(net "VR_FET_SW_P12V_STBY_PVPP_DEF")
			(options
				(clearance outline)
				(anchor circle)
			)
			(primitives
				(gr_poly
					(pts
						(arc
							(start 0.1397 0.2413)
							(mid 0 0.381)
							(end -0.1397 0.2413)
						)
						(xy -0.1397 -0.381) (xy 0.1397 -0.381)
					)
					(width 0)
					(fill yes)
				)
			)
		)
		(pad "40" smd custom
			(at -2.249932 -2.8321 90)
			(size 0.06985 0.06985)
			(layers "F.Cu" "F.Mask" "F.Paste")
			(net "FM_PVPP_PVDDQ_CPU0_EN_DEF")
			(options
				(clearance outline)
				(anchor circle)
			)
			(primitives
				(gr_poly
					(pts
						(arc
							(start 0.1397 0.2413)
							(mid 0 0.381)
							(end -0.1397 0.2413)
						)
						(xy -0.1397 -0.381) (xy 0.1397 -0.381)
					)
					(width 0)
					(fill yes)
				)
			)
		)
		(pad "41" smd rect
			(at -1.4478 -1.1938 90)
			(size 1.4986 2.0066)
			(layers "F.Cu" "F.Mask" "F.Paste")
			(net "GND")
		)
		(pad "42" smd rect
			(at -1.4478 1.1938 90)
			(size 1.4986 2.0066)
			(layers "F.Cu" "F.Mask" "F.Paste")
			(net "VR_FET_SW_P12V_STBY_PVPP_DEF")
		)
		(pad "43" smd rect
			(at 1.0033 0 90)
			(size 2.3876 4.3942)
			(layers "F.Cu" "F.Mask" "F.Paste")
			(net "VR_PVPP_DEF_PHASE")
		)
	)
)
